FILE_TYPE=LIBRARY_PARTS;
primitive '74LVC2G07DW7';
  pin
    '1A':
      PIN_NUMBER='(1)';
      INPUT_LOAD='(-0.01,0.01)';
    '2A':
      PIN_NUMBER='(3)';
      INPUT_LOAD='(-0.01,0.01)';
    '1Y':
      PIN_NUMBER='(6)';
      OUTPUT_LOAD='(1.0,-1.0)';
    '2Y':
      PIN_NUMBER='(4)';
      OUTPUT_LOAD='(1.0,-1.0)';
    'GND':
      PIN_NUMBER='(2)';
      PINUSE='POWER';
      NO_LOAD_CHECK='Both';
      NO_IO_CHECK='Both';
      NO_ASSERT_CHECK='TRUE';
      NO_DIR_CHECK='TRUE';
      ALLOW_CONNECT='TRUE';
    'VCC':
      PIN_NUMBER='(5)';
      PINUSE='POWER';
      NO_LOAD_CHECK='Both';
      NO_IO_CHECK='Both';
      NO_ASSERT_CHECK='TRUE';
      NO_DIR_CHECK='TRUE';
      ALLOW_CONNECT='TRUE';
  end_pin;
  body
    PART_NAME='74LVC2G07DW7';
    BODY_NAME='74LVC2G07DW7';
    PHYS_DES_PREFIX='U';
    CLASS='IC';
  end_body;
end_primitive;

END.
